(kicad_pcb
	(version 20260206)
	(generator "pcbnew")
	(generator_version "10.0")
	(general
		(thickness 1.6)
		(legacy_teardrops no)
	)
	(paper "A4")
	(title_block
		(title "Wiwynn_Tioga_Pass_MB.brd")
		(comment 1 "Tioga Pass / footprint 3283 of 4770 (J6T1), pads 124-243 of 291")
	)
	(layers
		(0 "F.Cu" signal "TOP")
		(4 "In1.Cu" signal "L2GND")
		(6 "In2.Cu" signal "L3")
		(8 "In3.Cu" signal "L4GND")
		(10 "In4.Cu" signal "L5")
		(12 "In5.Cu" signal "L6GND")
		(14 "In6.Cu" signal "L7VCC")
		(16 "In7.Cu" signal "L8VCC")
		(18 "In8.Cu" signal "L9GND")
		(20 "In9.Cu" signal "L10")
		(22 "In10.Cu" signal "L11GND")
		(24 "In11.Cu" signal "L12")
		(26 "In12.Cu" signal "L13GND")
		(2 "B.Cu" signal "BOTTOM")
		(9 "F.Adhes" user "F.Adhesive")
		(11 "B.Adhes" user "B.Adhesive")
		(13 "F.Paste" user "Package Geometry/Pastemask Top")
		(15 "B.Paste" user "Package Geometry/Pastemask Bottom")
		(5 "F.SilkS" user "Ref Des/Silkscreen Top")
		(7 "B.SilkS" user "Ref Des/Silkscreen Bottom")
		(1 "F.Mask" user "Board Geometry/Soldermask Top")
		(3 "B.Mask" user "Board Geometry/Soldermask Bottom")
		(17 "Dwgs.User" user "User.Drawings")
		(19 "Cmts.User" user "User.Comments")
		(21 "Eco1.User" user "User.Eco1")
		(23 "Eco2.User" user "User.Eco2")
		(25 "Edge.Cuts" user "Board Geometry/Outline")
		(27 "Margin" user)
		(31 "F.CrtYd" user "Package Geometry/Place Bound Top")
		(29 "B.CrtYd" user "Package Geometry/Place Bound Bottom")
		(35 "F.Fab" user "Ref Des/Assembly Top")
		(33 "B.Fab" user "Ref Des/Assembly Bottom")
	)
	(footprint ""
		(layer "B.Cu")
		(at 194.700398 -24.824182 90)
		(property "Reference" "J6T1"
			(at 2.200148 39.23411 0)
			(unlocked yes)
			(layer "B.SilkS")
			(effects
				(font
					(size 0.7874 0.5842)
					(thickness 0.1524)
				)
				(justify left mirror)
			)
		)
		(property "Value" ""
			(at 0 0 90)
			(layer "B.Fab")
			(effects
				(font
					(size 1.27 1.27)
				)
				(justify mirror)
			)
		)
		(duplicate_pad_numbers_are_jumpers no)
		(pad "121" smd rect
			(at 0 107.100116 270)
			(size 1.8034 0.508)
			(layers "B.Cu" "B.Mask" "B.Paste")
			(net "M_A_DQS_DP<15>")
		)
		(pad "122" smd rect
			(at 0 107.95 270)
			(size 1.8034 0.508)
			(layers "B.Cu" "B.Mask" "B.Paste")
			(net "M_A_DQS_DN<15>")
		)
		(pad "123" smd rect
			(at 0 108.799884 270)
			(size 1.8034 0.508)
			(layers "B.Cu" "B.Mask" "B.Paste")
			(net "GND")
		)
		(pad "124" smd rect
			(at 0 109.650022 270)
			(size 1.8034 0.508)
			(layers "B.Cu" "B.Mask" "B.Paste")
			(net "M_A_DQ<54>")
		)
		(pad "125" smd rect
			(at 0 110.499906 270)
			(size 1.8034 0.508)
			(layers "B.Cu" "B.Mask" "B.Paste")
			(net "GND")
		)
		(pad "126" smd rect
			(at 0 111.350044 270)
			(size 1.8034 0.508)
			(layers "B.Cu" "B.Mask" "B.Paste")
			(net "M_A_DQ<50>")
		)
		(pad "127" smd rect
			(at 0 112.199928 270)
			(size 1.8034 0.508)
			(layers "B.Cu" "B.Mask" "B.Paste")
			(net "GND")
		)
		(pad "128" smd rect
			(at 0 113.050066 270)
			(size 1.8034 0.508)
			(layers "B.Cu" "B.Mask" "B.Paste")
			(net "M_A_DQ<60>")
		)
		(pad "129" smd rect
			(at 0 113.89995 270)
			(size 1.8034 0.508)
			(layers "B.Cu" "B.Mask" "B.Paste")
			(net "GND")
		)
		(pad "130" smd rect
			(at 0 114.750088 270)
			(size 1.8034 0.508)
			(layers "B.Cu" "B.Mask" "B.Paste")
			(net "M_A_DQ<56>")
		)
		(pad "131" smd rect
			(at 0 115.599972 270)
			(size 1.8034 0.508)
			(layers "B.Cu" "B.Mask" "B.Paste")
			(net "GND")
		)
		(pad "132" smd rect
			(at 0 116.45011 270)
			(size 1.8034 0.508)
			(layers "B.Cu" "B.Mask" "B.Paste")
			(net "M_A_DQS_DP<16>")
		)
		(pad "133" smd rect
			(at 0 117.299994 270)
			(size 1.8034 0.508)
			(layers "B.Cu" "B.Mask" "B.Paste")
			(net "M_A_DQS_DN<16>")
		)
		(pad "134" smd rect
			(at 0 118.149878 270)
			(size 1.8034 0.508)
			(layers "B.Cu" "B.Mask" "B.Paste")
			(net "GND")
		)
		(pad "135" smd rect
			(at 0 119.000016 270)
			(size 1.8034 0.508)
			(layers "B.Cu" "B.Mask" "B.Paste")
			(net "M_A_DQ<62>")
		)
		(pad "136" smd rect
			(at 0 119.8499 270)
			(size 1.8034 0.508)
			(layers "B.Cu" "B.Mask" "B.Paste")
			(net "GND")
		)
		(pad "137" smd rect
			(at 0 120.700038 270)
			(size 1.8034 0.508)
			(layers "B.Cu" "B.Mask" "B.Paste")
			(net "M_A_DQ<58>")
		)
		(pad "138" smd rect
			(at 0 121.549922 270)
			(size 1.8034 0.508)
			(layers "B.Cu" "B.Mask" "B.Paste")
			(net "GND")
		)
		(pad "139" smd rect
			(at 0 122.40006 270)
			(size 1.8034 0.508)
			(layers "B.Cu" "B.Mask" "B.Paste")
			(net "PVPP_ABC")
		)
		(pad "140" smd rect
			(at 0 123.249944 270)
			(size 1.8034 0.508)
			(layers "B.Cu" "B.Mask" "B.Paste")
			(net "GND")
		)
		(pad "141" smd rect
			(at 0 124.100082 270)
			(size 1.8034 0.508)
			(layers "B.Cu" "B.Mask" "B.Paste")
			(net "SMB_DDR_ABC_VPP_SCL")
		)
		(pad "142" smd rect
			(at 0 124.949966 270)
			(size 1.8034 0.508)
			(layers "B.Cu" "B.Mask" "B.Paste")
			(net "PVPP_ABC")
		)
		(pad "143" smd rect
			(at 0 125.800104 270)
			(size 1.8034 0.508)
			(layers "B.Cu" "B.Mask" "B.Paste")
			(net "PVPP_ABC")
		)
		(pad "144" smd rect
			(at 0 126.649988 270)
			(size 1.8034 0.508)
			(layers "B.Cu" "B.Mask" "B.Paste")
			(net "TP_CH_A_DIMM_A1_RFU_2")
		)
		(pad "145" smd rect
			(at -4.59994 0 270)
			(size 1.8034 0.508)
			(layers "B.Cu" "B.Mask" "B.Paste")
			(net "P12V_NVDIMM_ABC")
		)
		(pad "146" smd rect
			(at -4.59994 0.849884 270)
			(size 1.8034 0.508)
			(layers "B.Cu" "B.Mask" "B.Paste")
			(net "M_A_VREF")
		)
		(pad "147" smd rect
			(at -4.59994 1.700022 270)
			(size 1.8034 0.508)
			(layers "B.Cu" "B.Mask" "B.Paste")
			(net "GND")
		)
		(pad "148" smd rect
			(at -4.59994 2.549906 270)
			(size 1.8034 0.508)
			(layers "B.Cu" "B.Mask" "B.Paste")
			(net "M_A_DQ<5>")
		)
		(pad "149" smd rect
			(at -4.59994 3.400044 270)
			(size 1.8034 0.508)
			(layers "B.Cu" "B.Mask" "B.Paste")
			(net "GND")
		)
		(pad "150" smd rect
			(at -4.59994 4.249928 270)
			(size 1.8034 0.508)
			(layers "B.Cu" "B.Mask" "B.Paste")
			(net "M_A_DQ<1>")
		)
		(pad "151" smd rect
			(at -4.59994 5.100066 270)
			(size 1.8034 0.508)
			(layers "B.Cu" "B.Mask" "B.Paste")
			(net "GND")
		)
		(pad "152" smd rect
			(at -4.59994 5.94995 270)
			(size 1.8034 0.508)
			(layers "B.Cu" "B.Mask" "B.Paste")
			(net "M_A_DQS_DN<0>")
		)
		(pad "153" smd rect
			(at -4.59994 6.800088 270)
			(size 1.8034 0.508)
			(layers "B.Cu" "B.Mask" "B.Paste")
			(net "M_A_DQS_DP<0>")
		)
		(pad "154" smd rect
			(at -4.59994 7.649972 270)
			(size 1.8034 0.508)
			(layers "B.Cu" "B.Mask" "B.Paste")
			(net "GND")
		)
		(pad "155" smd rect
			(at -4.59994 8.50011 270)
			(size 1.8034 0.508)
			(layers "B.Cu" "B.Mask" "B.Paste")
			(net "M_A_DQ<7>")
		)
		(pad "156" smd rect
			(at -4.59994 9.349994 270)
			(size 1.8034 0.508)
			(layers "B.Cu" "B.Mask" "B.Paste")
			(net "GND")
		)
		(pad "157" smd rect
			(at -4.59994 10.199878 270)
			(size 1.8034 0.508)
			(layers "B.Cu" "B.Mask" "B.Paste")
			(net "M_A_DQ<3>")
		)
		(pad "158" smd rect
			(at -4.59994 11.050016 270)
			(size 1.8034 0.508)
			(layers "B.Cu" "B.Mask" "B.Paste")
			(net "GND")
		)
		(pad "159" smd rect
			(at -4.59994 11.8999 270)
			(size 1.8034 0.508)
			(layers "B.Cu" "B.Mask" "B.Paste")
			(net "M_A_DQ<13>")
		)
		(pad "160" smd rect
			(at -4.59994 12.750038 270)
			(size 1.8034 0.508)
			(layers "B.Cu" "B.Mask" "B.Paste")
			(net "GND")
		)
		(pad "161" smd rect
			(at -4.59994 13.599922 270)
			(size 1.8034 0.508)
			(layers "B.Cu" "B.Mask" "B.Paste")
			(net "M_A_DQ<9>")
		)
		(pad "162" smd rect
			(at -4.59994 14.45006 270)
			(size 1.8034 0.508)
			(layers "B.Cu" "B.Mask" "B.Paste")
			(net "GND")
		)
		(pad "163" smd rect
			(at -4.59994 15.299944 270)
			(size 1.8034 0.508)
			(layers "B.Cu" "B.Mask" "B.Paste")
			(net "M_A_DQS_DN<1>")
		)
		(pad "164" smd rect
			(at -4.59994 16.150082 270)
			(size 1.8034 0.508)
			(layers "B.Cu" "B.Mask" "B.Paste")
			(net "M_A_DQS_DP<1>")
		)
		(pad "165" smd rect
			(at -4.59994 16.999966 270)
			(size 1.8034 0.508)
			(layers "B.Cu" "B.Mask" "B.Paste")
			(net "GND")
		)
		(pad "166" smd rect
			(at -4.59994 17.850104 270)
			(size 1.8034 0.508)
			(layers "B.Cu" "B.Mask" "B.Paste")
			(net "M_A_DQ<15>")
		)
		(pad "167" smd rect
			(at -4.59994 18.699988 270)
			(size 1.8034 0.508)
			(layers "B.Cu" "B.Mask" "B.Paste")
			(net "GND")
		)
		(pad "168" smd rect
			(at -4.59994 19.550126 270)
			(size 1.8034 0.508)
			(layers "B.Cu" "B.Mask" "B.Paste")
			(net "M_A_DQ<11>")
		)
		(pad "169" smd rect
			(at -4.59994 20.40001 270)
			(size 1.8034 0.508)
			(layers "B.Cu" "B.Mask" "B.Paste")
			(net "GND")
		)
		(pad "170" smd rect
			(at -4.59994 21.249894 270)
			(size 1.8034 0.508)
			(layers "B.Cu" "B.Mask" "B.Paste")
			(net "M_A_DQ<21>")
		)
		(pad "171" smd rect
			(at -4.59994 22.100032 270)
			(size 1.8034 0.508)
			(layers "B.Cu" "B.Mask" "B.Paste")
			(net "GND")
		)
		(pad "172" smd rect
			(at -4.59994 22.949916 270)
			(size 1.8034 0.508)
			(layers "B.Cu" "B.Mask" "B.Paste")
			(net "M_A_DQ<17>")
		)
		(pad "173" smd rect
			(at -4.59994 23.800054 270)
			(size 1.8034 0.508)
			(layers "B.Cu" "B.Mask" "B.Paste")
			(net "GND")
		)
		(pad "174" smd rect
			(at -4.59994 24.649938 270)
			(size 1.8034 0.508)
			(layers "B.Cu" "B.Mask" "B.Paste")
			(net "M_A_DQS_DN<2>")
		)
		(pad "175" smd rect
			(at -4.59994 25.500076 270)
			(size 1.8034 0.508)
			(layers "B.Cu" "B.Mask" "B.Paste")
			(net "M_A_DQS_DP<2>")
		)
		(pad "176" smd rect
			(at -4.59994 26.34996 270)
			(size 1.8034 0.508)
			(layers "B.Cu" "B.Mask" "B.Paste")
			(net "GND")
		)
		(pad "177" smd rect
			(at -4.59994 27.200098 270)
			(size 1.8034 0.508)
			(layers "B.Cu" "B.Mask" "B.Paste")
			(net "M_A_DQ<23>")
		)
		(pad "178" smd rect
			(at -4.59994 28.049982 270)
			(size 1.8034 0.508)
			(layers "B.Cu" "B.Mask" "B.Paste")
			(net "GND")
		)
		(pad "179" smd rect
			(at -4.59994 28.90012 270)
			(size 1.8034 0.508)
			(layers "B.Cu" "B.Mask" "B.Paste")
			(net "M_A_DQ<19>")
		)
		(pad "180" smd rect
			(at -4.59994 29.750004 270)
			(size 1.8034 0.508)
			(layers "B.Cu" "B.Mask" "B.Paste")
			(net "GND")
		)
		(pad "181" smd rect
			(at -4.59994 30.599888 270)
			(size 1.8034 0.508)
			(layers "B.Cu" "B.Mask" "B.Paste")
			(net "M_A_DQ<29>")
		)
		(pad "182" smd rect
			(at -4.59994 31.450026 270)
			(size 1.8034 0.508)
			(layers "B.Cu" "B.Mask" "B.Paste")
			(net "GND")
		)
		(pad "183" smd rect
			(at -4.59994 32.29991 270)
			(size 1.8034 0.508)
			(layers "B.Cu" "B.Mask" "B.Paste")
			(net "M_A_DQ<25>")
		)
		(pad "184" smd rect
			(at -4.59994 33.150048 270)
			(size 1.8034 0.508)
			(layers "B.Cu" "B.Mask" "B.Paste")
			(net "GND")
		)
		(pad "185" smd rect
			(at -4.59994 33.999932 270)
			(size 1.8034 0.508)
			(layers "B.Cu" "B.Mask" "B.Paste")
			(net "M_A_DQS_DN<3>")
		)
		(pad "186" smd rect
			(at -4.59994 34.85007 270)
			(size 1.8034 0.508)
			(layers "B.Cu" "B.Mask" "B.Paste")
			(net "M_A_DQS_DP<3>")
		)
		(pad "187" smd rect
			(at -4.59994 35.699954 270)
			(size 1.8034 0.508)
			(layers "B.Cu" "B.Mask" "B.Paste")
			(net "GND")
		)
		(pad "188" smd rect
			(at -4.59994 36.550092 270)
			(size 1.8034 0.508)
			(layers "B.Cu" "B.Mask" "B.Paste")
			(net "M_A_DQ<31>")
		)
		(pad "189" smd rect
			(at -4.59994 37.399976 270)
			(size 1.8034 0.508)
			(layers "B.Cu" "B.Mask" "B.Paste")
			(net "GND")
		)
		(pad "190" smd rect
			(at -4.59994 38.250114 270)
			(size 1.8034 0.508)
			(layers "B.Cu" "B.Mask" "B.Paste")
			(net "M_A_DQ<27>")
		)
		(pad "191" smd rect
			(at -4.59994 39.099998 270)
			(size 1.8034 0.508)
			(layers "B.Cu" "B.Mask" "B.Paste")
			(net "GND")
		)
		(pad "192" smd rect
			(at -4.59994 39.949882 270)
			(size 1.8034 0.508)
			(layers "B.Cu" "B.Mask" "B.Paste")
			(net "M_A_ECC<5>")
		)
		(pad "193" smd rect
			(at -4.59994 40.80002 270)
			(size 1.8034 0.508)
			(layers "B.Cu" "B.Mask" "B.Paste")
			(net "GND")
		)
		(pad "194" smd rect
			(at -4.59994 41.649904 270)
			(size 1.8034 0.508)
			(layers "B.Cu" "B.Mask" "B.Paste")
			(net "M_A_ECC<1>")
		)
		(pad "195" smd rect
			(at -4.59994 42.500042 270)
			(size 1.8034 0.508)
			(layers "B.Cu" "B.Mask" "B.Paste")
			(net "GND")
		)
		(pad "196" smd rect
			(at -4.59994 43.349926 270)
			(size 1.8034 0.508)
			(layers "B.Cu" "B.Mask" "B.Paste")
			(net "M_A_DQS_DN<8>")
		)
		(pad "197" smd rect
			(at -4.59994 44.200064 270)
			(size 1.8034 0.508)
			(layers "B.Cu" "B.Mask" "B.Paste")
			(net "M_A_DQS_DP<8>")
		)
		(pad "198" smd rect
			(at -4.59994 45.049948 270)
			(size 1.8034 0.508)
			(layers "B.Cu" "B.Mask" "B.Paste")
			(net "GND")
		)
		(pad "199" smd rect
			(at -4.59994 45.900086 270)
			(size 1.8034 0.508)
			(layers "B.Cu" "B.Mask" "B.Paste")
			(net "M_A_ECC<7>")
		)
		(pad "200" smd rect
			(at -4.59994 46.74997 270)
			(size 1.8034 0.508)
			(layers "B.Cu" "B.Mask" "B.Paste")
			(net "GND")
		)
		(pad "201" smd rect
			(at -4.59994 47.600108 270)
			(size 1.8034 0.508)
			(layers "B.Cu" "B.Mask" "B.Paste")
			(net "M_A_ECC<3>")
		)
		(pad "202" smd rect
			(at -4.59994 48.449992 270)
			(size 1.8034 0.508)
			(layers "B.Cu" "B.Mask" "B.Paste")
			(net "GND")
		)
		(pad "203" smd rect
			(at -4.59994 49.299876 270)
			(size 1.8034 0.508)
			(layers "B.Cu" "B.Mask" "B.Paste")
			(net "M_A_CKE<3>")
		)
		(pad "204" smd rect
			(at -4.59994 50.150014 270)
			(size 1.8034 0.508)
			(layers "B.Cu" "B.Mask" "B.Paste")
			(net "PVDDQ_ABC")
		)
		(pad "205" smd rect
			(at -4.59994 50.999898 270)
			(size 1.8034 0.508)
			(layers "B.Cu" "B.Mask" "B.Paste")
			(net "TP_CH_A_DIMM_A1_RFU_0")
		)
		(pad "206" smd rect
			(at -4.59994 51.850036 270)
			(size 1.8034 0.508)
			(layers "B.Cu" "B.Mask" "B.Paste")
			(net "PVDDQ_ABC")
		)
		(pad "207" smd rect
			(at -4.59994 52.69992 270)
			(size 1.8034 0.508)
			(layers "B.Cu" "B.Mask" "B.Paste")
			(net "M_A_BG<1>")
		)
		(pad "208" smd rect
			(at -4.59994 53.550058 270)
			(size 1.8034 0.508)
			(layers "B.Cu" "B.Mask" "B.Paste")
			(net "M_A_ALERT_N")
		)
		(pad "209" smd rect
			(at -4.59994 54.399942 270)
			(size 1.8034 0.508)
			(layers "B.Cu" "B.Mask" "B.Paste")
			(net "PVDDQ_ABC")
		)
		(pad "210" smd rect
			(at -4.59994 55.25008 270)
			(size 1.8034 0.508)
			(layers "B.Cu" "B.Mask" "B.Paste")
			(net "M_A_MA<11>")
		)
		(pad "211" smd rect
			(at -4.59994 56.099964 270)
			(size 1.8034 0.508)
			(layers "B.Cu" "B.Mask" "B.Paste")
			(net "M_A_MA<7>")
		)
		(pad "212" smd rect
			(at -4.59994 56.950102 270)
			(size 1.8034 0.508)
			(layers "B.Cu" "B.Mask" "B.Paste")
			(net "PVDDQ_ABC")
		)
		(pad "213" smd rect
			(at -4.59994 57.799986 270)
			(size 1.8034 0.508)
			(layers "B.Cu" "B.Mask" "B.Paste")
			(net "M_A_MA<5>")
		)
		(pad "214" smd rect
			(at -4.59994 58.650124 270)
			(size 1.8034 0.508)
			(layers "B.Cu" "B.Mask" "B.Paste")
			(net "M_A_MA<4>")
		)
		(pad "215" smd rect
			(at -4.59994 59.500008 270)
			(size 1.8034 0.508)
			(layers "B.Cu" "B.Mask" "B.Paste")
			(net "PVDDQ_ABC")
		)
		(pad "216" smd rect
			(at -4.59994 60.349892 270)
			(size 1.8034 0.508)
			(layers "B.Cu" "B.Mask" "B.Paste")
			(net "M_A_MA<2>")
		)
		(pad "217" smd rect
			(at -4.59994 61.20003 270)
			(size 1.8034 0.508)
			(layers "B.Cu" "B.Mask" "B.Paste")
			(net "PVDDQ_ABC")
		)
		(pad "218" smd rect
			(at -4.59994 62.049914 270)
			(size 1.8034 0.508)
			(layers "B.Cu" "B.Mask" "B.Paste")
			(net "M_A_CLK_DP<3>")
		)
		(pad "219" smd rect
			(at -4.59994 62.900052 270)
			(size 1.8034 0.508)
			(layers "B.Cu" "B.Mask" "B.Paste")
			(net "M_A_CLK_DN<3>")
		)
		(pad "220" smd rect
			(at -4.59994 63.749936 270)
			(size 1.8034 0.508)
			(layers "B.Cu" "B.Mask" "B.Paste")
			(net "PVDDQ_ABC")
		)
		(pad "221" smd rect
			(at -4.59994 64.600074 270)
			(size 1.8034 0.508)
			(layers "B.Cu" "B.Mask" "B.Paste")
			(net "PVTT_ABC")
		)
		(pad "222" smd rect
			(at -4.59994 70.550024 270)
			(size 1.8034 0.508)
			(layers "B.Cu" "B.Mask" "B.Paste")
			(net "M_A_PAR")
		)
		(pad "223" smd rect
			(at -4.59994 71.399908 270)
			(size 1.8034 0.508)
			(layers "B.Cu" "B.Mask" "B.Paste")
			(net "PVDDQ_ABC")
		)
		(pad "224" smd rect
			(at -4.59994 72.250046 270)
			(size 1.8034 0.508)
			(layers "B.Cu" "B.Mask" "B.Paste")
			(net "M_A_BA<1>")
		)
		(pad "225" smd rect
			(at -4.59994 73.09993 270)
			(size 1.8034 0.508)
			(layers "B.Cu" "B.Mask" "B.Paste")
			(net "M_A_MA<10>")
		)
		(pad "226" smd rect
			(at -4.59994 73.950068 270)
			(size 1.8034 0.508)
			(layers "B.Cu" "B.Mask" "B.Paste")
			(net "PVDDQ_ABC")
		)
		(pad "227" smd rect
			(at -4.59994 74.799952 270)
			(size 1.8034 0.508)
			(layers "B.Cu" "B.Mask" "B.Paste")
			(net "TP_CH_A_DIMM_A1_RFU_1")
		)
		(pad "228" smd rect
			(at -4.59994 75.65009 270)
			(size 1.8034 0.508)
			(layers "B.Cu" "B.Mask" "B.Paste")
			(net "M_A_MA<14>")
		)
		(pad "229" smd rect
			(at -4.59994 76.499974 270)
			(size 1.8034 0.508)
			(layers "B.Cu" "B.Mask" "B.Paste")
			(net "PVDDQ_ABC")
		)
		(pad "230" smd rect
			(at -4.59994 77.350112 270)
			(size 1.8034 0.508)
			(layers "B.Cu" "B.Mask" "B.Paste")
			(net "FM_ADR_COMPLETE_ABC_N")
		)
		(pad "231" smd rect
			(at -4.59994 78.199996 270)
			(size 1.8034 0.508)
			(layers "B.Cu" "B.Mask" "B.Paste")
			(net "PVDDQ_ABC")
		)
		(pad "232" smd rect
			(at -4.59994 79.04988 270)
			(size 1.8034 0.508)
			(layers "B.Cu" "B.Mask" "B.Paste")
			(net "M_A_MA<13>")
		)
		(pad "233" smd rect
			(at -4.59994 79.900018 270)
			(size 1.8034 0.508)
			(layers "B.Cu" "B.Mask" "B.Paste")
			(net "PVDDQ_ABC")
		)
		(pad "234" smd rect
			(at -4.59994 80.749902 270)
			(size 1.8034 0.508)
			(layers "B.Cu" "B.Mask" "B.Paste")
			(net "M_A_MA<17>")
		)
		(pad "235" smd rect
			(at -4.59994 81.60004 270)
			(size 1.8034 0.508)
			(layers "B.Cu" "B.Mask" "B.Paste")
			(net "M_A_C<2>")
		)
		(pad "236" smd rect
			(at -4.59994 82.449924 270)
			(size 1.8034 0.508)
			(layers "B.Cu" "B.Mask" "B.Paste")
			(net "PVDDQ_ABC")
		)
		(pad "237" smd rect
			(at -4.59994 83.300062 270)
			(size 1.8034 0.508)
			(layers "B.Cu" "B.Mask" "B.Paste")
			(net "M_A_CS_N<7>")
		)
		(pad "238" smd rect
			(at -4.59994 84.149946 270)
			(size 1.8034 0.508)
			(layers "B.Cu" "B.Mask" "B.Paste")
			(net "GND")
		)
		(pad "239" smd rect
			(at -4.59994 85.000084 270)
			(size 1.8034 0.508)
			(layers "B.Cu" "B.Mask" "B.Paste")
			(net "GND")
		)
		(pad "240" smd rect
			(at -4.59994 85.849968 270)
			(size 1.8034 0.508)
			(layers "B.Cu" "B.Mask" "B.Paste")
			(net "M_A_DQ<37>")
		)
	)
)
